# T6G (Grand Teton) — schematic netlist excerpt (pin names and nets, part order shuffled) for the footprints in the layout excerpt that follows; sources: Cadence DE-HDL packaged netlist, KiCad conversion of 04192023_DAF0TMB3IC0_F0TG_MB_C_brd_V02_OCP.brd

R3112  Q_RES  33.2 1% CHIP  pkg 0402LF  page 248 : A = I3C_BMC_SWB_SCL ; B = I3C_BMC_SWB_R_SCL
C1883  Q_CAP  10UF 25V 10% X6S  pkg C0805  page 233 : A = VFG3P3_CLK_GEN ; B = GND
R8066  Q_RES  33 5% CHIP  pkg 0402LF  page 200 : A = PWRGD_PVDDIO_P0 ; B = PWRGD_PVDDIO_P0_R

(kicad_pcb
	(version 20260206)
	(generator "pcbnew")
	(generator_version "10.0")
	(general
		(thickness 1.6)
		(legacy_teardrops no)
	)
	(paper "A4")
	(title_block
		(title "04192023_DAF0TMB3IC0_F0TG_MB_C_brd_V02_OCP.brd")
		(comment 1 "Grand Teton / footprints 5635-5637 of 8354")
	)
	(layers
		(0 "F.Cu" signal "TOP")
		(4 "In1.Cu" signal "GND")
		(6 "In2.Cu" signal "IN1")
		(8 "In3.Cu" signal "GND1")
		(10 "In4.Cu" signal "IN2")
		(12 "In5.Cu" signal "GND2")
		(14 "In6.Cu" signal "IN3")
		(16 "In7.Cu" signal "GND3")
		(18 "In8.Cu" signal "VCC")
		(20 "In9.Cu" signal "VCC1")
		(22 "In10.Cu" signal "GND4")
		(24 "In11.Cu" signal "IN4")
		(26 "In12.Cu" signal "GND5")
		(28 "In13.Cu" signal "IN5")
		(30 "In14.Cu" signal "GND6")
		(32 "In15.Cu" signal "IN6")
		(34 "In16.Cu" signal "GND7")
		(2 "B.Cu" signal "BOTTOM")
		(9 "F.Adhes" user "F.Adhesive")
		(11 "B.Adhes" user "B.Adhesive")
		(13 "F.Paste" user "Package Geometry/Pastemask Top")
		(15 "B.Paste" user "Package Geometry/Pastemask Bottom")
		(5 "F.SilkS" user "Ref Des/Silkscreen Top")
		(7 "B.SilkS" user "Ref Des/Silkscreen Bottom")
		(1 "F.Mask" user "Board Geometry/Soldermask Top")
		(3 "B.Mask" user "Board Geometry/Soldermask Bottom")
		(17 "Dwgs.User" user "User.Drawings")
		(19 "Cmts.User" user "User.Comments")
		(21 "Eco1.User" user "User.Eco1")
		(23 "Eco2.User" user "User.Eco2")
		(25 "Edge.Cuts" user "Board Geometry/Outline")
		(27 "Margin" user)
		(31 "F.CrtYd" user "Package Geometry/Place Bound Top")
		(29 "B.CrtYd" user "Package Geometry/Place Bound Bottom")
		(35 "F.Fab" user "Ref Des/Assembly Top")
		(33 "B.Fab" user "Ref Des/Assembly Bottom")
	)
	(footprint ""
		(layer "B.Cu")
		(at 172.285914 -13.635228 -90)
		(property "Reference" "R3112"
			(at 0 0 90)
			(layer "B.SilkS")
			(hide yes)
			(effects
				(font
					(size 1.27 1.27)
				)
				(justify mirror)
			)
		)
		(property "Value" ""
			(at 0 0 90)
			(layer "B.Fab")
			(effects
				(font
					(size 1.27 1.27)
				)
				(justify mirror)
			)
		)
		(duplicate_pad_numbers_are_jumpers no)
		(fp_line
			(start -0.7874 0.4064)
			(end 0.7874 0.4064)
			(stroke
				(width 0.1524)
				(type default)
			)
			(layer "B.SilkS")
		)
		(fp_line
			(start 0.7874 0.4064)
			(end 0.7874 -0.4064)
			(stroke
				(width 0.1524)
				(type default)
			)
			(layer "B.SilkS")
		)
		(fp_line
			(start -0.7874 -0.4064)
			(end -0.7874 0.4064)
			(stroke
				(width 0.1524)
				(type default)
			)
			(layer "B.SilkS")
		)
		(fp_line
			(start 0.7874 -0.4064)
			(end -0.7874 -0.4064)
			(stroke
				(width 0.1524)
				(type default)
			)
			(layer "B.SilkS")
		)
		(fp_line
			(start -0.67945 0.3048)
			(end -0.120396 0.3048)
			(stroke
				(width 0.1)
				(type default)
			)
			(layer "B.Fab")
		)
		(fp_line
			(start -0.120396 0.3048)
			(end -0.120396 0.2794)
			(stroke
				(width 0.1)
				(type default)
			)
			(layer "B.Fab")
		)
		(fp_line
			(start 0.12065 0.3048)
			(end 0.67945 0.3048)
			(stroke
				(width 0.1)
				(type default)
			)
			(layer "B.Fab")
		)
		(fp_line
			(start 0.67945 0.3048)
			(end 0.67945 -0.305054)
			(stroke
				(width 0.1)
				(type default)
			)
			(layer "B.Fab")
		)
		(fp_line
			(start -0.120396 0.2794)
			(end 0.12065 0.2794)
			(stroke
				(width 0.1)
				(type default)
			)
			(layer "B.Fab")
		)
		(fp_line
			(start 0.12065 0.2794)
			(end 0.12065 0.3048)
			(stroke
				(width 0.1)
				(type default)
			)
			(layer "B.Fab")
		)
		(fp_line
			(start -0.12065 -0.2794)
			(end -0.12065 -0.3048)
			(stroke
				(width 0.1)
				(type default)
			)
			(layer "B.Fab")
		)
		(fp_line
			(start 0.12065 -0.2794)
			(end -0.12065 -0.2794)
			(stroke
				(width 0.1)
				(type default)
			)
			(layer "B.Fab")
		)
		(fp_line
			(start -0.67945 -0.3048)
			(end -0.67945 0.3048)
			(stroke
				(width 0.1)
				(type default)
			)
			(layer "B.Fab")
		)
		(fp_line
			(start -0.12065 -0.3048)
			(end -0.67945 -0.3048)
			(stroke
				(width 0.1)
				(type default)
			)
			(layer "B.Fab")
		)
		(fp_line
			(start 0.12065 -0.305054)
			(end 0.12065 -0.2794)
			(stroke
				(width 0.1)
				(type default)
			)
			(layer "B.Fab")
		)
		(fp_line
			(start 0.67945 -0.305054)
			(end 0.12065 -0.305054)
			(stroke
				(width 0.1)
				(type default)
			)
			(layer "B.Fab")
		)
		(pad "1" smd circle
			(at 0.40005 0 90)
			(size 0 0)
			(layers "B.Cu" "B.Mask" "B.Paste")
			(net "I3C_BMC_SWB_SCL")
		)
		(pad "2" smd circle
			(at -0.40005 0 90)
			(size 0 0)
			(layers "B.Cu" "B.Mask" "B.Paste")
			(net "I3C_BMC_SWB_R_SCL")
		)
	)
	(footprint ""
		(layer "B.Cu")
		(at 10.886694 -136.97839)
		(property "Reference" "C1883"
			(at 0 0 0)
			(layer "B.SilkS")
			(hide yes)
			(effects
				(font
					(size 1.27 1.27)
				)
				(justify mirror)
			)
		)
		(property "Value" ""
			(at 0 0 0)
			(layer "B.Fab")
			(effects
				(font
					(size 1.27 1.27)
				)
				(justify mirror)
			)
		)
		(duplicate_pad_numbers_are_jumpers no)
		(fp_line
			(start -1.524 -0.762)
			(end -1.524 0.762)
			(stroke
				(width 0.1524)
				(type default)
			)
			(layer "B.SilkS")
		)
		(fp_line
			(start -1.524 0.762)
			(end 1.524 0.762)
			(stroke
				(width 0.1524)
				(type default)
			)
			(layer "B.SilkS")
		)
		(fp_line
			(start 1.524 -0.762)
			(end -1.524 -0.762)
			(stroke
				(width 0.1524)
				(type default)
			)
			(layer "B.SilkS")
		)
		(fp_line
			(start 1.524 0.762)
			(end 1.524 -0.762)
			(stroke
				(width 0.1524)
				(type default)
			)
			(layer "B.SilkS")
		)
		(fp_line
			(start -1.1049 -0.724916)
			(end 1.1049 -0.724916)
			(stroke
				(width 0.1)
				(type default)
			)
			(layer "B.Fab")
		)
		(fp_line
			(start -1.1049 0.724916)
			(end -1.1049 -0.724916)
			(stroke
				(width 0.1)
				(type default)
			)
			(layer "B.Fab")
		)
		(fp_line
			(start 1.1049 -0.724916)
			(end 1.1049 0.724916)
			(stroke
				(width 0.1)
				(type default)
			)
			(layer "B.Fab")
		)
		(fp_line
			(start 1.1049 0.724916)
			(end -1.1049 0.724916)
			(stroke
				(width 0.1)
				(type default)
			)
			(layer "B.Fab")
		)
		(pad "1" smd rect
			(at 0.889 0)
			(size 1.016 1.27)
			(layers "B.Cu" "B.Mask" "B.Paste")
			(net "VFG3P3_CLK_GEN")
		)
		(pad "2" smd rect
			(at -0.889 0)
			(size 1.016 1.27)
			(layers "B.Cu" "B.Mask" "B.Paste")
			(net "GND")
		)
	)
	(footprint ""
		(layer "B.Cu")
		(at 304.419 -358.14 180)
		(property "Reference" "R8066"
			(at 0 0 0)
			(layer "B.SilkS")
			(hide yes)
			(effects
				(font
					(size 1.27 1.27)
				)
				(justify mirror)
			)
		)
		(property "Value" ""
			(at 0 0 0)
			(layer "B.Fab")
			(effects
				(font
					(size 1.27 1.27)
				)
				(justify mirror)
			)
		)
		(duplicate_pad_numbers_are_jumpers no)
		(fp_line
			(start 0.7874 0.4064)
			(end 0.7874 -0.4064)
			(stroke
				(width 0.1524)
				(type default)
			)
			(layer "B.SilkS")
		)
		(fp_line
			(start 0.7874 -0.4064)
			(end -0.7874 -0.4064)
			(stroke
				(width 0.1524)
				(type default)
			)
			(layer "B.SilkS")
		)
		(fp_line
			(start -0.7874 0.4064)
			(end 0.7874 0.4064)
			(stroke
				(width 0.1524)
				(type default)
			)
			(layer "B.SilkS")
		)
		(fp_line
			(start -0.7874 -0.4064)
			(end -0.7874 0.4064)
			(stroke
				(width 0.1524)
				(type default)
			)
			(layer "B.SilkS")
		)
		(fp_line
			(start 0.67945 0.3048)
			(end 0.67945 -0.305054)
			(stroke
				(width 0.1)
				(type default)
			)
			(layer "B.Fab")
		)
		(fp_line
			(start 0.67945 -0.305054)
			(end 0.12065 -0.305054)
			(stroke
				(width 0.1)
				(type default)
			)
			(layer "B.Fab")
		)
		(fp_line
			(start 0.12065 0.3048)
			(end 0.67945 0.3048)
			(stroke
				(width 0.1)
				(type default)
			)
			(layer "B.Fab")
		)
		(fp_line
			(start 0.12065 0.2794)
			(end 0.12065 0.3048)
			(stroke
				(width 0.1)
				(type default)
			)
			(layer "B.Fab")
		)
		(fp_line
			(start 0.12065 -0.2794)
			(end -0.12065 -0.2794)
			(stroke
				(width 0.1)
				(type default)
			)
			(layer "B.Fab")
		)
		(fp_line
			(start 0.12065 -0.305054)
			(end 0.12065 -0.2794)
			(stroke
				(width 0.1)
				(type default)
			)
			(layer "B.Fab")
		)
		(fp_line
			(start -0.120396 0.3048)
			(end -0.120396 0.2794)
			(stroke
				(width 0.1)
				(type default)
			)
			(layer "B.Fab")
		)
		(fp_line
			(start -0.120396 0.2794)
			(end 0.12065 0.2794)
			(stroke
				(width 0.1)
				(type default)
			)
			(layer "B.Fab")
		)
		(fp_line
			(start -0.12065 -0.2794)
			(end -0.12065 -0.3048)
			(stroke
				(width 0.1)
				(type default)
			)
			(layer "B.Fab")
		)
		(fp_line
			(start -0.12065 -0.3048)
			(end -0.67945 -0.3048)
			(stroke
				(width 0.1)
				(type default)
			)
			(layer "B.Fab")
		)
		(fp_line
			(start -0.67945 0.3048)
			(end -0.120396 0.3048)
			(stroke
				(width 0.1)
				(type default)
			)
			(layer "B.Fab")
		)
		(fp_line
			(start -0.67945 -0.3048)
			(end -0.67945 0.3048)
			(stroke
				(width 0.1)
				(type default)
			)
			(layer "B.Fab")
		)
		(pad "1" smd circle
			(at 0.40005 0)
			(size 0 0)
			(layers "B.Cu" "B.Mask" "B.Paste")
			(net "PWRGD_PVDDIO_P0")
		)
		(pad "2" smd circle
			(at -0.40005 0)
			(size 0 0)
			(layers "B.Cu" "B.Mask" "B.Paste")
			(net "PWRGD_PVDDIO_P0_R")
		)
	)
)
